(kicad_pcb
	(version 20260206)
	(generator "pcbnew")
	(generator_version "10.0")
	(general
		(thickness 1.6)
		(legacy_teardrops no)
	)
	(paper "A4")
	(title_block
		(title "12092022_DA0F0TMDCD0_F0T_Management_Board_D_brd_V3_OCP.brd")
		(comment 1 "Grand Teton / footprints 473-478 of 1440")
	)
	(layers
		(0 "F.Cu" signal "TOP")
		(4 "In1.Cu" signal "GND")
		(6 "In2.Cu" signal "IN1")
		(8 "In3.Cu" signal "GND1")
		(10 "In4.Cu" signal "IN2")
		(12 "In5.Cu" signal "VCC")
		(14 "In6.Cu" signal "VCC1")
		(16 "In7.Cu" signal "IN3")
		(18 "In8.Cu" signal "GND2")
		(20 "In9.Cu" signal "IN4")
		(22 "In10.Cu" signal "GND3")
		(2 "B.Cu" signal "BOTTOM")
		(9 "F.Adhes" user "F.Adhesive")
		(11 "B.Adhes" user "B.Adhesive")
		(13 "F.Paste" user "Package Geometry/Pastemask Top")
		(15 "B.Paste" user "Package Geometry/Pastemask Bottom")
		(5 "F.SilkS" user "Ref Des/Silkscreen Top")
		(7 "B.SilkS" user "Ref Des/Silkscreen Bottom")
		(1 "F.Mask" user "Board Geometry/Soldermask Top")
		(3 "B.Mask" user "Board Geometry/Soldermask Bottom")
		(17 "Dwgs.User" user "User.Drawings")
		(19 "Cmts.User" user "User.Comments")
		(21 "Eco1.User" user "User.Eco1")
		(23 "Eco2.User" user "User.Eco2")
		(25 "Edge.Cuts" user "Board Geometry/Outline")
		(27 "Margin" user)
		(31 "F.CrtYd" user "Package Geometry/Place Bound Top")
		(29 "B.CrtYd" user "Package Geometry/Place Bound Bottom")
		(35 "F.Fab" user "Ref Des/Assembly Top")
		(33 "B.Fab" user "Ref Des/Assembly Bottom")
	)
	(footprint ""
		(layer "F.Cu")
		(at 70.4088 -29.845 -90)
		(property "Reference" "C252"
			(at 0 0 270)
			(layer "F.SilkS")
			(hide yes)
			(effects
				(font
					(size 1.27 1.27)
				)
			)
		)
		(property "Value" ""
			(at 0 0 270)
			(layer "F.Fab")
			(effects
				(font
					(size 1.27 1.27)
				)
			)
		)
		(duplicate_pad_numbers_are_jumpers no)
		(fp_line
			(start -0.7874 0.4064)
			(end -0.7874 -0.4064)
			(stroke
				(width 0.1524)
				(type default)
			)
			(layer "F.SilkS")
		)
		(fp_line
			(start 0.7874 0.4064)
			(end -0.7874 0.4064)
			(stroke
				(width 0.1524)
				(type default)
			)
			(layer "F.SilkS")
		)
		(fp_line
			(start -0.7874 -0.4064)
			(end 0.7874 -0.4064)
			(stroke
				(width 0.1524)
				(type default)
			)
			(layer "F.SilkS")
		)
		(fp_line
			(start 0.7874 -0.4064)
			(end 0.7874 0.4064)
			(stroke
				(width 0.1524)
				(type default)
			)
			(layer "F.SilkS")
		)
		(fp_line
			(start -0.67945 0.3048)
			(end -0.67945 -0.305054)
			(stroke
				(width 0.1)
				(type default)
			)
			(layer "F.Fab")
		)
		(fp_line
			(start -0.12065 0.3048)
			(end -0.67945 0.3048)
			(stroke
				(width 0.1)
				(type default)
			)
			(layer "F.Fab")
		)
		(fp_line
			(start 0.120396 0.3048)
			(end 0.120396 0.2794)
			(stroke
				(width 0.1)
				(type default)
			)
			(layer "F.Fab")
		)
		(fp_line
			(start 0.67945 0.3048)
			(end 0.120396 0.3048)
			(stroke
				(width 0.1)
				(type default)
			)
			(layer "F.Fab")
		)
		(fp_line
			(start -0.12065 0.2794)
			(end -0.12065 0.3048)
			(stroke
				(width 0.1)
				(type default)
			)
			(layer "F.Fab")
		)
		(fp_line
			(start 0.120396 0.2794)
			(end -0.12065 0.2794)
			(stroke
				(width 0.1)
				(type default)
			)
			(layer "F.Fab")
		)
		(fp_line
			(start -0.12065 -0.2794)
			(end 0.12065 -0.2794)
			(stroke
				(width 0.1)
				(type default)
			)
			(layer "F.Fab")
		)
		(fp_line
			(start 0.12065 -0.2794)
			(end 0.12065 -0.3048)
			(stroke
				(width 0.1)
				(type default)
			)
			(layer "F.Fab")
		)
		(fp_line
			(start 0.12065 -0.3048)
			(end 0.67945 -0.3048)
			(stroke
				(width 0.1)
				(type default)
			)
			(layer "F.Fab")
		)
		(fp_line
			(start 0.67945 -0.3048)
			(end 0.67945 0.3048)
			(stroke
				(width 0.1)
				(type default)
			)
			(layer "F.Fab")
		)
		(fp_line
			(start -0.67945 -0.305054)
			(end -0.12065 -0.305054)
			(stroke
				(width 0.1)
				(type default)
			)
			(layer "F.Fab")
		)
		(fp_line
			(start -0.12065 -0.305054)
			(end -0.12065 -0.2794)
			(stroke
				(width 0.1)
				(type default)
			)
			(layer "F.Fab")
		)
		(pad "1" smd circle
			(at -0.40005 0 270)
			(size 0 0)
			(layers "F.Cu" "F.Mask" "F.Paste")
			(net "PWRGD_P3V3_RGM_R")
		)
		(pad "2" smd circle
			(at 0.40005 0 270)
			(size 0 0)
			(layers "F.Cu" "F.Mask" "F.Paste")
			(net "GND")
		)
	)
	(footprint ""
		(layer "F.Cu")
		(at 85.2932 -17.78 180)
		(property "Reference" "R504"
			(at 0 0 180)
			(layer "F.SilkS")
			(hide yes)
			(effects
				(font
					(size 1.27 1.27)
				)
			)
		)
		(property "Value" ""
			(at 0 0 180)
			(layer "F.Fab")
			(effects
				(font
					(size 1.27 1.27)
				)
			)
		)
		(duplicate_pad_numbers_are_jumpers no)
		(fp_line
			(start 0.7874 0.4064)
			(end -0.7874 0.4064)
			(stroke
				(width 0.1524)
				(type default)
			)
			(layer "F.SilkS")
		)
		(fp_line
			(start 0.7874 -0.4064)
			(end 0.7874 0.4064)
			(stroke
				(width 0.1524)
				(type default)
			)
			(layer "F.SilkS")
		)
		(fp_line
			(start -0.7874 0.4064)
			(end -0.7874 -0.4064)
			(stroke
				(width 0.1524)
				(type default)
			)
			(layer "F.SilkS")
		)
		(fp_line
			(start -0.7874 -0.4064)
			(end 0.7874 -0.4064)
			(stroke
				(width 0.1524)
				(type default)
			)
			(layer "F.SilkS")
		)
		(fp_line
			(start 0.67945 0.3048)
			(end 0.120396 0.3048)
			(stroke
				(width 0.1)
				(type default)
			)
			(layer "F.Fab")
		)
		(fp_line
			(start 0.67945 -0.3048)
			(end 0.67945 0.3048)
			(stroke
				(width 0.1)
				(type default)
			)
			(layer "F.Fab")
		)
		(fp_line
			(start 0.12065 -0.2794)
			(end 0.12065 -0.3048)
			(stroke
				(width 0.1)
				(type default)
			)
			(layer "F.Fab")
		)
		(fp_line
			(start 0.12065 -0.3048)
			(end 0.67945 -0.3048)
			(stroke
				(width 0.1)
				(type default)
			)
			(layer "F.Fab")
		)
		(fp_line
			(start 0.120396 0.3048)
			(end 0.120396 0.2794)
			(stroke
				(width 0.1)
				(type default)
			)
			(layer "F.Fab")
		)
		(fp_line
			(start 0.120396 0.2794)
			(end -0.12065 0.2794)
			(stroke
				(width 0.1)
				(type default)
			)
			(layer "F.Fab")
		)
		(fp_line
			(start -0.12065 0.3048)
			(end -0.67945 0.3048)
			(stroke
				(width 0.1)
				(type default)
			)
			(layer "F.Fab")
		)
		(fp_line
			(start -0.12065 0.2794)
			(end -0.12065 0.3048)
			(stroke
				(width 0.1)
				(type default)
			)
			(layer "F.Fab")
		)
		(fp_line
			(start -0.12065 -0.2794)
			(end 0.12065 -0.2794)
			(stroke
				(width 0.1)
				(type default)
			)
			(layer "F.Fab")
		)
		(fp_line
			(start -0.12065 -0.305054)
			(end -0.12065 -0.2794)
			(stroke
				(width 0.1)
				(type default)
			)
			(layer "F.Fab")
		)
		(fp_line
			(start -0.67945 0.3048)
			(end -0.67945 -0.305054)
			(stroke
				(width 0.1)
				(type default)
			)
			(layer "F.Fab")
		)
		(fp_line
			(start -0.67945 -0.305054)
			(end -0.12065 -0.305054)
			(stroke
				(width 0.1)
				(type default)
			)
			(layer "F.Fab")
		)
		(pad "1" smd circle
			(at -0.40005 0 180)
			(size 0 0)
			(layers "F.Cu" "F.Mask" "F.Paste")
			(net "P3V3_AUX")
		)
		(pad "2" smd circle
			(at 0.40005 0 180)
			(size 0 0)
			(layers "F.Cu" "F.Mask" "F.Paste")
			(net "REAR_ID_RST_BTN_N")
		)
	)
	(footprint ""
		(layer "F.Cu")
		(at 8.128 -82.55)
		(property "Reference" "U6"
			(at 2.45237 0.3048 90)
			(unlocked yes)
			(layer "F.SilkS")
			(effects
				(font
					(size 0.7874 0.5842)
					(thickness 0.1524)
				)
				(justify left)
			)
		)
		(property "Value" ""
			(at 0 0 0)
			(layer "F.Fab")
			(effects
				(font
					(size 1.27 1.27)
				)
			)
		)
		(duplicate_pad_numbers_are_jumpers no)
		(fp_line
			(start -1.38176 -1.100074)
			(end -1.38176 1.100074)
			(stroke
				(width 0.1524)
				(type default)
			)
			(layer "F.SilkS")
		)
		(fp_line
			(start -1.38176 1.100074)
			(end 1.38176 1.100074)
			(stroke
				(width 0.1524)
				(type default)
			)
			(layer "F.SilkS")
		)
		(fp_line
			(start -0.592074 -1.100074)
			(end -1.38176 -1.100074)
			(stroke
				(width 0.1524)
				(type default)
			)
			(layer "F.SilkS")
		)
		(fp_line
			(start 0 -0.508)
			(end -0.592074 -1.100074)
			(stroke
				(width 0.1524)
				(type default)
			)
			(layer "F.SilkS")
		)
		(fp_line
			(start 0.592074 -1.100074)
			(end 0 -0.508)
			(stroke
				(width 0.1524)
				(type default)
			)
			(layer "F.SilkS")
		)
		(fp_line
			(start 1.38176 -1.100074)
			(end 0.592074 -1.100074)
			(stroke
				(width 0.1524)
				(type default)
			)
			(layer "F.SilkS")
		)
		(fp_line
			(start 1.38176 1.100074)
			(end 1.38176 -1.100074)
			(stroke
				(width 0.1524)
				(type default)
			)
			(layer "F.SilkS")
		)
		(fp_poly
			(pts
				(xy -1.9431 -0.870204) (xy -1.50241 -0.649986) (xy -1.9431 -0.429768)
			)
			(stroke
				(width 0)
				(type default)
			)
			(fill yes)
			(layer "F.SilkS")
		)
		(fp_line
			(start -0.674878 -1.100074)
			(end -0.674878 1.100074)
			(stroke
				(width 0.1)
				(type default)
			)
			(layer "F.Fab")
		)
		(fp_line
			(start -0.674878 1.100074)
			(end 0.674878 1.100074)
			(stroke
				(width 0.1)
				(type default)
			)
			(layer "F.Fab")
		)
		(fp_line
			(start 0.674878 -1.100074)
			(end -0.674878 -1.100074)
			(stroke
				(width 0.1)
				(type default)
			)
			(layer "F.Fab")
		)
		(fp_line
			(start 0.674878 1.100074)
			(end 0.674878 -1.100074)
			(stroke
				(width 0.1)
				(type default)
			)
			(layer "F.Fab")
		)
		(fp_poly
			(pts
				(xy -1.9431 -0.870204) (xy -1.50241 -0.649986) (xy -1.9431 -0.429768)
			)
			(stroke
				(width 0)
				(type default)
			)
			(fill yes)
			(layer "F.Fab")
		)
		(pad "1" smd rect
			(at -0.94996 -0.649986 270)
			(size 0.4318 0.6096)
			(layers "F.Cu" "F.Mask" "F.Paste")
			(net "PWRGD_P1V0_AUX_DELAY")
		)
		(pad "2" smd rect
			(at -0.94996 0 270)
			(size 0.4318 0.6096)
			(layers "F.Cu" "F.Mask" "F.Paste")
			(net "GND")
		)
		(pad "3" smd rect
			(at -0.94996 0.649986 270)
			(size 0.4318 0.6096)
			(layers "F.Cu" "F.Mask" "F.Paste")
			(net "RST_SRST_PLD_BMC_R1_N")
		)
		(pad "4" smd rect
			(at 0.94996 0.649986 270)
			(size 0.4318 0.6096)
			(layers "F.Cu" "F.Mask" "F.Paste")
			(net "RST_SRST_PLD_BMC_BUF_N")
		)
		(pad "5" smd rect
			(at 0.94996 0 270)
			(size 0.4318 0.6096)
			(layers "F.Cu" "F.Mask" "F.Paste")
			(net "P3V3_AUX")
		)
		(pad "6" smd rect
			(at 0.94996 -0.649986 270)
			(size 0.4318 0.6096)
			(layers "F.Cu" "F.Mask" "F.Paste")
			(net "PWRGD_P1V0_AUX_DELAY_BUF")
		)
	)
	(footprint ""
		(layer "F.Cu")
		(at 85.29955 -41.887394 180)
		(property "Reference" "R339"
			(at 0 0 180)
			(layer "F.SilkS")
			(hide yes)
			(effects
				(font
					(size 1.27 1.27)
				)
			)
		)
		(property "Value" ""
			(at 0 0 180)
			(layer "F.Fab")
			(effects
				(font
					(size 1.27 1.27)
				)
			)
		)
		(duplicate_pad_numbers_are_jumpers no)
		(fp_line
			(start 0.7874 0.4064)
			(end -0.7874 0.4064)
			(stroke
				(width 0.1524)
				(type default)
			)
			(layer "F.SilkS")
		)
		(fp_line
			(start 0.7874 -0.4064)
			(end 0.7874 0.4064)
			(stroke
				(width 0.1524)
				(type default)
			)
			(layer "F.SilkS")
		)
		(fp_line
			(start -0.7874 0.4064)
			(end -0.7874 -0.4064)
			(stroke
				(width 0.1524)
				(type default)
			)
			(layer "F.SilkS")
		)
		(fp_line
			(start -0.7874 -0.4064)
			(end 0.7874 -0.4064)
			(stroke
				(width 0.1524)
				(type default)
			)
			(layer "F.SilkS")
		)
		(fp_line
			(start 0.67945 0.3048)
			(end 0.120396 0.3048)
			(stroke
				(width 0.1)
				(type default)
			)
			(layer "F.Fab")
		)
		(fp_line
			(start 0.67945 -0.3048)
			(end 0.67945 0.3048)
			(stroke
				(width 0.1)
				(type default)
			)
			(layer "F.Fab")
		)
		(fp_line
			(start 0.12065 -0.2794)
			(end 0.12065 -0.3048)
			(stroke
				(width 0.1)
				(type default)
			)
			(layer "F.Fab")
		)
		(fp_line
			(start 0.12065 -0.3048)
			(end 0.67945 -0.3048)
			(stroke
				(width 0.1)
				(type default)
			)
			(layer "F.Fab")
		)
		(fp_line
			(start 0.120396 0.3048)
			(end 0.120396 0.2794)
			(stroke
				(width 0.1)
				(type default)
			)
			(layer "F.Fab")
		)
		(fp_line
			(start 0.120396 0.2794)
			(end -0.12065 0.2794)
			(stroke
				(width 0.1)
				(type default)
			)
			(layer "F.Fab")
		)
		(fp_line
			(start -0.12065 0.3048)
			(end -0.67945 0.3048)
			(stroke
				(width 0.1)
				(type default)
			)
			(layer "F.Fab")
		)
		(fp_line
			(start -0.12065 0.2794)
			(end -0.12065 0.3048)
			(stroke
				(width 0.1)
				(type default)
			)
			(layer "F.Fab")
		)
		(fp_line
			(start -0.12065 -0.2794)
			(end 0.12065 -0.2794)
			(stroke
				(width 0.1)
				(type default)
			)
			(layer "F.Fab")
		)
		(fp_line
			(start -0.12065 -0.305054)
			(end -0.12065 -0.2794)
			(stroke
				(width 0.1)
				(type default)
			)
			(layer "F.Fab")
		)
		(fp_line
			(start -0.67945 0.3048)
			(end -0.67945 -0.305054)
			(stroke
				(width 0.1)
				(type default)
			)
			(layer "F.Fab")
		)
		(fp_line
			(start -0.67945 -0.305054)
			(end -0.12065 -0.305054)
			(stroke
				(width 0.1)
				(type default)
			)
			(layer "F.Fab")
		)
		(pad "1" smd circle
			(at -0.40005 0 180)
			(size 0 0)
			(layers "F.Cu" "F.Mask" "F.Paste")
			(net "GND")
		)
		(pad "2" smd circle
			(at 0.40005 0 180)
			(size 0 0)
			(layers "F.Cu" "F.Mask" "F.Paste")
			(net "M_BMC_DDR4_MA<13>")
		)
	)
	(footprint ""
		(layer "F.Cu")
		(at 53.7718 -109.3978 -90)
		(property "Reference" "R861"
			(at 0 0 270)
			(layer "F.SilkS")
			(hide yes)
			(effects
				(font
					(size 1.27 1.27)
				)
			)
		)
		(property "Value" ""
			(at 0 0 270)
			(layer "F.Fab")
			(effects
				(font
					(size 1.27 1.27)
				)
			)
		)
		(duplicate_pad_numbers_are_jumpers no)
		(fp_line
			(start -0.7874 0.4064)
			(end -0.7874 -0.4064)
			(stroke
				(width 0.1524)
				(type default)
			)
			(layer "F.SilkS")
		)
		(fp_line
			(start 0.7874 0.4064)
			(end -0.7874 0.4064)
			(stroke
				(width 0.1524)
				(type default)
			)
			(layer "F.SilkS")
		)
		(fp_line
			(start -0.7874 -0.4064)
			(end 0.7874 -0.4064)
			(stroke
				(width 0.1524)
				(type default)
			)
			(layer "F.SilkS")
		)
		(fp_line
			(start 0.7874 -0.4064)
			(end 0.7874 0.4064)
			(stroke
				(width 0.1524)
				(type default)
			)
			(layer "F.SilkS")
		)
		(fp_line
			(start -0.67945 0.3048)
			(end -0.67945 -0.305054)
			(stroke
				(width 0.1)
				(type default)
			)
			(layer "F.Fab")
		)
		(fp_line
			(start -0.12065 0.3048)
			(end -0.67945 0.3048)
			(stroke
				(width 0.1)
				(type default)
			)
			(layer "F.Fab")
		)
		(fp_line
			(start 0.120396 0.3048)
			(end 0.120396 0.2794)
			(stroke
				(width 0.1)
				(type default)
			)
			(layer "F.Fab")
		)
		(fp_line
			(start 0.67945 0.3048)
			(end 0.120396 0.3048)
			(stroke
				(width 0.1)
				(type default)
			)
			(layer "F.Fab")
		)
		(fp_line
			(start -0.12065 0.2794)
			(end -0.12065 0.3048)
			(stroke
				(width 0.1)
				(type default)
			)
			(layer "F.Fab")
		)
		(fp_line
			(start 0.120396 0.2794)
			(end -0.12065 0.2794)
			(stroke
				(width 0.1)
				(type default)
			)
			(layer "F.Fab")
		)
		(fp_line
			(start -0.12065 -0.2794)
			(end 0.12065 -0.2794)
			(stroke
				(width 0.1)
				(type default)
			)
			(layer "F.Fab")
		)
		(fp_line
			(start 0.12065 -0.2794)
			(end 0.12065 -0.3048)
			(stroke
				(width 0.1)
				(type default)
			)
			(layer "F.Fab")
		)
		(fp_line
			(start 0.12065 -0.3048)
			(end 0.67945 -0.3048)
			(stroke
				(width 0.1)
				(type default)
			)
			(layer "F.Fab")
		)
		(fp_line
			(start 0.67945 -0.3048)
			(end 0.67945 0.3048)
			(stroke
				(width 0.1)
				(type default)
			)
			(layer "F.Fab")
		)
		(fp_line
			(start -0.67945 -0.305054)
			(end -0.12065 -0.305054)
			(stroke
				(width 0.1)
				(type default)
			)
			(layer "F.Fab")
		)
		(fp_line
			(start -0.12065 -0.305054)
			(end -0.12065 -0.2794)
			(stroke
				(width 0.1)
				(type default)
			)
			(layer "F.Fab")
		)
		(pad "1" smd circle
			(at -0.40005 0 270)
			(size 0 0)
			(layers "F.Cu" "F.Mask" "F.Paste")
			(net "SPI_SYS_R_MISO")
		)
		(pad "2" smd circle
			(at 0.40005 0 270)
			(size 0 0)
			(layers "F.Cu" "F.Mask" "F.Paste")
			(net "SPI_SYS_MUX_MISO")
		)
	)
	(footprint ""
		(layer "F.Cu")
		(at 30.5562 -86.995 180)
		(property "Reference" "R718"
			(at 0 0 180)
			(layer "F.SilkS")
			(hide yes)
			(effects
				(font
					(size 1.27 1.27)
				)
			)
		)
		(property "Value" ""
			(at 0 0 180)
			(layer "F.Fab")
			(effects
				(font
					(size 1.27 1.27)
				)
			)
		)
		(duplicate_pad_numbers_are_jumpers no)
		(fp_line
			(start 0.7874 0.4064)
			(end -0.7874 0.4064)
			(stroke
				(width 0.1524)
				(type default)
			)
			(layer "F.SilkS")
		)
		(fp_line
			(start 0.7874 -0.4064)
			(end 0.7874 0.4064)
			(stroke
				(width 0.1524)
				(type default)
			)
			(layer "F.SilkS")
		)
		(fp_line
			(start -0.7874 0.4064)
			(end -0.7874 -0.4064)
			(stroke
				(width 0.1524)
				(type default)
			)
			(layer "F.SilkS")
		)
		(fp_line
			(start -0.7874 -0.4064)
			(end 0.7874 -0.4064)
			(stroke
				(width 0.1524)
				(type default)
			)
			(layer "F.SilkS")
		)
		(fp_line
			(start 0.67945 0.3048)
			(end 0.120396 0.3048)
			(stroke
				(width 0.1)
				(type default)
			)
			(layer "F.Fab")
		)
		(fp_line
			(start 0.67945 -0.3048)
			(end 0.67945 0.3048)
			(stroke
				(width 0.1)
				(type default)
			)
			(layer "F.Fab")
		)
		(fp_line
			(start 0.12065 -0.2794)
			(end 0.12065 -0.3048)
			(stroke
				(width 0.1)
				(type default)
			)
			(layer "F.Fab")
		)
		(fp_line
			(start 0.12065 -0.3048)
			(end 0.67945 -0.3048)
			(stroke
				(width 0.1)
				(type default)
			)
			(layer "F.Fab")
		)
		(fp_line
			(start 0.120396 0.3048)
			(end 0.120396 0.2794)
			(stroke
				(width 0.1)
				(type default)
			)
			(layer "F.Fab")
		)
		(fp_line
			(start 0.120396 0.2794)
			(end -0.12065 0.2794)
			(stroke
				(width 0.1)
				(type default)
			)
			(layer "F.Fab")
		)
		(fp_line
			(start -0.12065 0.3048)
			(end -0.67945 0.3048)
			(stroke
				(width 0.1)
				(type default)
			)
			(layer "F.Fab")
		)
		(fp_line
			(start -0.12065 0.2794)
			(end -0.12065 0.3048)
			(stroke
				(width 0.1)
				(type default)
			)
			(layer "F.Fab")
		)
		(fp_line
			(start -0.12065 -0.2794)
			(end 0.12065 -0.2794)
			(stroke
				(width 0.1)
				(type default)
			)
			(layer "F.Fab")
		)
		(fp_line
			(start -0.12065 -0.305054)
			(end -0.12065 -0.2794)
			(stroke
				(width 0.1)
				(type default)
			)
			(layer "F.Fab")
		)
		(fp_line
			(start -0.67945 0.3048)
			(end -0.67945 -0.305054)
			(stroke
				(width 0.1)
				(type default)
			)
			(layer "F.Fab")
		)
		(fp_line
			(start -0.67945 -0.305054)
			(end -0.12065 -0.305054)
			(stroke
				(width 0.1)
				(type default)
			)
			(layer "F.Fab")
		)
		(pad "1" smd circle
			(at -0.40005 0 180)
			(size 0 0)
			(layers "F.Cu" "F.Mask" "F.Paste")
			(net "RST_PLTRST_N")
		)
		(pad "2" smd circle
			(at 0.40005 0 180)
			(size 0 0)
			(layers "F.Cu" "F.Mask" "F.Paste")
			(net "RST_PLTRST_R1_N")
		)
	)
)
